# T6G (Grand Teton) — schematic netlist excerpt (pin names and nets, part order shuffled) for the footprints in the layout excerpt that follows; sources: Cadence DE-HDL packaged netlist, KiCad conversion of 04192023_DAF0TMB3IC0_F0TG_MB_C_brd_V02_OCP.brd

C845  Q_CAP_DIFFBUS  DIFF BUS_0.22UF 6.3V 20% X6S  pkg C0201  page 64 : \1\ = P5E_CPU0_P2_TX_C_DP<12> ; \2\ = P5E_CPU0_P2_TX_DP<12>
PC208  Q_CAP  560PF 50V 10% EMPTY  pkg C0402  page 220 : A = SW_PVDDCR_CPU1_P1_SW6 ; B = SW_PVDDCR_CPU1_P1_SW6_RC
PR3961  Q_RES  6.8K 1% CHIP  pkg 0402LF  page 146 : A = P12V_E1S_UV_0 ; B = P12V_E1S_OV_0

(kicad_pcb
	(version 20260206)
	(generator "pcbnew")
	(generator_version "10.0")
	(general
		(thickness 1.6)
		(legacy_teardrops no)
	)
	(paper "A4")
	(title_block
		(title "04192023_DAF0TMB3IC0_F0TG_MB_C_brd_V02_OCP.brd")
		(comment 1 "Grand Teton / footprints 4062-4064 of 8354")
	)
	(layers
		(0 "F.Cu" signal "TOP")
		(4 "In1.Cu" signal "GND")
		(6 "In2.Cu" signal "IN1")
		(8 "In3.Cu" signal "GND1")
		(10 "In4.Cu" signal "IN2")
		(12 "In5.Cu" signal "GND2")
		(14 "In6.Cu" signal "IN3")
		(16 "In7.Cu" signal "GND3")
		(18 "In8.Cu" signal "VCC")
		(20 "In9.Cu" signal "VCC1")
		(22 "In10.Cu" signal "GND4")
		(24 "In11.Cu" signal "IN4")
		(26 "In12.Cu" signal "GND5")
		(28 "In13.Cu" signal "IN5")
		(30 "In14.Cu" signal "GND6")
		(32 "In15.Cu" signal "IN6")
		(34 "In16.Cu" signal "GND7")
		(2 "B.Cu" signal "BOTTOM")
		(9 "F.Adhes" user "F.Adhesive")
		(11 "B.Adhes" user "B.Adhesive")
		(13 "F.Paste" user "Package Geometry/Pastemask Top")
		(15 "B.Paste" user "Package Geometry/Pastemask Bottom")
		(5 "F.SilkS" user "Ref Des/Silkscreen Top")
		(7 "B.SilkS" user "Ref Des/Silkscreen Bottom")
		(1 "F.Mask" user "Board Geometry/Soldermask Top")
		(3 "B.Mask" user "Board Geometry/Soldermask Bottom")
		(17 "Dwgs.User" user "User.Drawings")
		(19 "Cmts.User" user "User.Comments")
		(21 "Eco1.User" user "User.Eco1")
		(23 "Eco2.User" user "User.Eco2")
		(25 "Edge.Cuts" user "Board Geometry/Outline")
		(27 "Margin" user)
		(31 "F.CrtYd" user "Package Geometry/Place Bound Top")
		(29 "B.CrtYd" user "Package Geometry/Place Bound Bottom")
		(35 "F.Fab" user "Ref Des/Assembly Top")
		(33 "B.Fab" user "Ref Des/Assembly Bottom")
	)
	(footprint ""
		(layer "F.Cu")
		(at 249.916696 -44.572682 180)
		(property "Reference" "PR3961"
			(at 0 0 180)
			(layer "F.SilkS")
			(hide yes)
			(effects
				(font
					(size 1.27 1.27)
				)
			)
		)
		(property "Value" ""
			(at 0 0 180)
			(layer "F.Fab")
			(effects
				(font
					(size 1.27 1.27)
				)
			)
		)
		(duplicate_pad_numbers_are_jumpers no)
		(fp_line
			(start 0.7874 0.4064)
			(end -0.7874 0.4064)
			(stroke
				(width 0.1524)
				(type default)
			)
			(layer "F.SilkS")
		)
		(fp_line
			(start 0.7874 -0.4064)
			(end 0.7874 0.4064)
			(stroke
				(width 0.1524)
				(type default)
			)
			(layer "F.SilkS")
		)
		(fp_line
			(start -0.7874 0.4064)
			(end -0.7874 -0.4064)
			(stroke
				(width 0.1524)
				(type default)
			)
			(layer "F.SilkS")
		)
		(fp_line
			(start -0.7874 -0.4064)
			(end 0.7874 -0.4064)
			(stroke
				(width 0.1524)
				(type default)
			)
			(layer "F.SilkS")
		)
		(fp_line
			(start 0.67945 0.3048)
			(end 0.120396 0.3048)
			(stroke
				(width 0.1)
				(type default)
			)
			(layer "F.Fab")
		)
		(fp_line
			(start 0.67945 -0.3048)
			(end 0.67945 0.3048)
			(stroke
				(width 0.1)
				(type default)
			)
			(layer "F.Fab")
		)
		(fp_line
			(start 0.12065 -0.2794)
			(end 0.12065 -0.3048)
			(stroke
				(width 0.1)
				(type default)
			)
			(layer "F.Fab")
		)
		(fp_line
			(start 0.12065 -0.3048)
			(end 0.67945 -0.3048)
			(stroke
				(width 0.1)
				(type default)
			)
			(layer "F.Fab")
		)
		(fp_line
			(start 0.120396 0.3048)
			(end 0.120396 0.2794)
			(stroke
				(width 0.1)
				(type default)
			)
			(layer "F.Fab")
		)
		(fp_line
			(start 0.120396 0.2794)
			(end -0.12065 0.2794)
			(stroke
				(width 0.1)
				(type default)
			)
			(layer "F.Fab")
		)
		(fp_line
			(start -0.12065 0.3048)
			(end -0.67945 0.3048)
			(stroke
				(width 0.1)
				(type default)
			)
			(layer "F.Fab")
		)
		(fp_line
			(start -0.12065 0.2794)
			(end -0.12065 0.3048)
			(stroke
				(width 0.1)
				(type default)
			)
			(layer "F.Fab")
		)
		(fp_line
			(start -0.12065 -0.2794)
			(end 0.12065 -0.2794)
			(stroke
				(width 0.1)
				(type default)
			)
			(layer "F.Fab")
		)
		(fp_line
			(start -0.12065 -0.305054)
			(end -0.12065 -0.2794)
			(stroke
				(width 0.1)
				(type default)
			)
			(layer "F.Fab")
		)
		(fp_line
			(start -0.67945 0.3048)
			(end -0.67945 -0.305054)
			(stroke
				(width 0.1)
				(type default)
			)
			(layer "F.Fab")
		)
		(fp_line
			(start -0.67945 -0.305054)
			(end -0.12065 -0.305054)
			(stroke
				(width 0.1)
				(type default)
			)
			(layer "F.Fab")
		)
		(pad "1" smd circle
			(at -0.40005 0 180)
			(size 0 0)
			(layers "F.Cu" "F.Mask" "F.Paste")
			(net "P12V_E1S_UV_0")
		)
		(pad "2" smd circle
			(at 0.40005 0 180)
			(size 0 0)
			(layers "F.Cu" "F.Mask" "F.Paste")
			(net "P12V_E1S_OV_0")
		)
	)
	(footprint ""
		(layer "F.Cu")
		(at 420.74084 -378.95403 -90)
		(property "Reference" "C845"
			(at 0 0 270)
			(layer "F.SilkS")
			(hide yes)
			(effects
				(font
					(size 1.27 1.27)
				)
			)
		)
		(property "Value" ""
			(at 0 0 270)
			(layer "F.Fab")
			(effects
				(font
					(size 1.27 1.27)
				)
			)
		)
		(duplicate_pad_numbers_are_jumpers no)
		(fp_line
			(start -0.299974 0.150114)
			(end -0.299974 -0.150114)
			(stroke
				(width 0.1)
				(type default)
			)
			(layer "F.Fab")
		)
		(fp_line
			(start 0.299974 0.150114)
			(end -0.299974 0.150114)
			(stroke
				(width 0.1)
				(type default)
			)
			(layer "F.Fab")
		)
		(fp_line
			(start -0.299974 -0.150114)
			(end 0.299974 -0.150114)
			(stroke
				(width 0.1)
				(type default)
			)
			(layer "F.Fab")
		)
		(fp_line
			(start 0.299974 -0.150114)
			(end 0.299974 0.150114)
			(stroke
				(width 0.1)
				(type default)
			)
			(layer "F.Fab")
		)
		(pad "1" smd rect
			(at -0.2667 0 270)
			(size 0.3048 0.381)
			(layers "F.Cu" "F.Mask" "F.Paste")
			(net "P5E_CPU0_P2_TX_C_DP<12>")
		)
		(pad "2" smd rect
			(at 0.2667 0 270)
			(size 0.3048 0.381)
			(layers "F.Cu" "F.Mask" "F.Paste")
			(net "P5E_CPU0_P2_TX_DP<12>")
		)
	)
	(footprint ""
		(layer "F.Cu")
		(at 100.03536 -336.935064 180)
		(property "Reference" "PC208"
			(at 0 0 180)
			(layer "F.SilkS")
			(hide yes)
			(effects
				(font
					(size 1.27 1.27)
				)
			)
		)
		(property "Value" ""
			(at 0 0 180)
			(layer "F.Fab")
			(effects
				(font
					(size 1.27 1.27)
				)
			)
		)
		(duplicate_pad_numbers_are_jumpers no)
		(fp_line
			(start 0.7874 0.4064)
			(end -0.7874 0.4064)
			(stroke
				(width 0.1524)
				(type default)
			)
			(layer "F.SilkS")
		)
		(fp_line
			(start 0.7874 -0.4064)
			(end 0.7874 0.4064)
			(stroke
				(width 0.1524)
				(type default)
			)
			(layer "F.SilkS")
		)
		(fp_line
			(start -0.7874 0.4064)
			(end -0.7874 -0.4064)
			(stroke
				(width 0.1524)
				(type default)
			)
			(layer "F.SilkS")
		)
		(fp_line
			(start -0.7874 -0.4064)
			(end 0.7874 -0.4064)
			(stroke
				(width 0.1524)
				(type default)
			)
			(layer "F.SilkS")
		)
		(fp_line
			(start 0.67945 0.3048)
			(end 0.120396 0.3048)
			(stroke
				(width 0.1)
				(type default)
			)
			(layer "F.Fab")
		)
		(fp_line
			(start 0.67945 -0.3048)
			(end 0.67945 0.3048)
			(stroke
				(width 0.1)
				(type default)
			)
			(layer "F.Fab")
		)
		(fp_line
			(start 0.12065 -0.2794)
			(end 0.12065 -0.3048)
			(stroke
				(width 0.1)
				(type default)
			)
			(layer "F.Fab")
		)
		(fp_line
			(start 0.12065 -0.3048)
			(end 0.67945 -0.3048)
			(stroke
				(width 0.1)
				(type default)
			)
			(layer "F.Fab")
		)
		(fp_line
			(start 0.120396 0.3048)
			(end 0.120396 0.2794)
			(stroke
				(width 0.1)
				(type default)
			)
			(layer "F.Fab")
		)
		(fp_line
			(start 0.120396 0.2794)
			(end -0.12065 0.2794)
			(stroke
				(width 0.1)
				(type default)
			)
			(layer "F.Fab")
		)
		(fp_line
			(start -0.12065 0.3048)
			(end -0.67945 0.3048)
			(stroke
				(width 0.1)
				(type default)
			)
			(layer "F.Fab")
		)
		(fp_line
			(start -0.12065 0.2794)
			(end -0.12065 0.3048)
			(stroke
				(width 0.1)
				(type default)
			)
			(layer "F.Fab")
		)
		(fp_line
			(start -0.12065 -0.2794)
			(end 0.12065 -0.2794)
			(stroke
				(width 0.1)
				(type default)
			)
			(layer "F.Fab")
		)
		(fp_line
			(start -0.12065 -0.305054)
			(end -0.12065 -0.2794)
			(stroke
				(width 0.1)
				(type default)
			)
			(layer "F.Fab")
		)
		(fp_line
			(start -0.67945 0.3048)
			(end -0.67945 -0.305054)
			(stroke
				(width 0.1)
				(type default)
			)
			(layer "F.Fab")
		)
		(fp_line
			(start -0.67945 -0.305054)
			(end -0.12065 -0.305054)
			(stroke
				(width 0.1)
				(type default)
			)
			(layer "F.Fab")
		)
		(pad "1" smd circle
			(at -0.40005 0 180)
			(size 0 0)
			(layers "F.Cu" "F.Mask" "F.Paste")
			(net "SW_PVDDCR_CPU1_P1_SW6")
		)
		(pad "2" smd circle
			(at 0.40005 0 180)
			(size 0 0)
			(layers "F.Cu" "F.Mask" "F.Paste")
			(net "SW_PVDDCR_CPU1_P1_SW6_RC")
		)
	)
)
